# T6G (Grand Teton) — schematic netlist excerpt (pin names and nets, part order shuffled) for the footprints in the layout excerpt that follows; sources: Cadence DE-HDL packaged netlist, KiCad conversion of 04192023_DAF0TMB3IC0_F0TG_MB_C_brd_V02_OCP.brd

J119  PICOPROBE_BXA  DELTA-L 4.0 EMPTY  pkg TRIANG_LAUNCH_3PXB  page 229
  \1_p\  = DELTA_L_85_10INCH_IN6_DP
  \2_n\  = DELTA_L_85_10INCH_IN6_DN
  \3_g\  = DELTA_L_GND_1

R910  Q_RES  200 1% CHIP  pkg 0201LF  page 353 : A = RT_CPU1_P3_SCAN_MODE ; B = GND

(kicad_pcb
	(version 20260206)
	(generator "pcbnew")
	(generator_version "10.0")
	(general
		(thickness 1.6)
		(legacy_teardrops no)
	)
	(paper "A4")
	(title_block
		(title "04192023_DAF0TMB3IC0_F0TG_MB_C_brd_V02_OCP.brd")
		(comment 1 "Grand Teton / footprints 6467-6468 of 8354")
	)
	(layers
		(0 "F.Cu" signal "TOP")
		(4 "In1.Cu" signal "GND")
		(6 "In2.Cu" signal "IN1")
		(8 "In3.Cu" signal "GND1")
		(10 "In4.Cu" signal "IN2")
		(12 "In5.Cu" signal "GND2")
		(14 "In6.Cu" signal "IN3")
		(16 "In7.Cu" signal "GND3")
		(18 "In8.Cu" signal "VCC")
		(20 "In9.Cu" signal "VCC1")
		(22 "In10.Cu" signal "GND4")
		(24 "In11.Cu" signal "IN4")
		(26 "In12.Cu" signal "GND5")
		(28 "In13.Cu" signal "IN5")
		(30 "In14.Cu" signal "GND6")
		(32 "In15.Cu" signal "IN6")
		(34 "In16.Cu" signal "GND7")
		(2 "B.Cu" signal "BOTTOM")
		(9 "F.Adhes" user "F.Adhesive")
		(11 "B.Adhes" user "B.Adhesive")
		(13 "F.Paste" user "Package Geometry/Pastemask Top")
		(15 "B.Paste" user "Package Geometry/Pastemask Bottom")
		(5 "F.SilkS" user "Ref Des/Silkscreen Top")
		(7 "B.SilkS" user "Ref Des/Silkscreen Bottom")
		(1 "F.Mask" user "Board Geometry/Soldermask Top")
		(3 "B.Mask" user "Board Geometry/Soldermask Bottom")
		(17 "Dwgs.User" user "User.Drawings")
		(19 "Cmts.User" user "User.Comments")
		(21 "Eco1.User" user "User.Eco1")
		(23 "Eco2.User" user "User.Eco2")
		(25 "Edge.Cuts" user "Board Geometry/Outline")
		(27 "Margin" user)
		(31 "F.CrtYd" user "Package Geometry/Place Bound Top")
		(29 "B.CrtYd" user "Package Geometry/Place Bound Bottom")
		(35 "F.Fab" user "Ref Des/Assembly Top")
		(33 "B.Fab" user "Ref Des/Assembly Bottom")
	)
	(footprint ""
		(layer "B.Cu")
		(at 300.538388 2.542794)
		(property "Reference" "J119"
			(at 4.387088 1.491742 270)
			(unlocked yes)
			(layer "B.SilkS")
			(effects
				(font
					(size 0.7874 0.5842)
					(thickness 0.1524)
				)
				(justify left mirror)
			)
		)
		(property "Value" ""
			(at 0 0 0)
			(layer "B.Fab")
			(effects
				(font
					(size 1.27 1.27)
				)
				(justify mirror)
			)
		)
		(duplicate_pad_numbers_are_jumpers no)
		(fp_line
			(start -1.2192 -2.06756)
			(end -1.2192 2.06756)
			(stroke
				(width 0.1524)
				(type default)
			)
			(layer "B.SilkS")
		)
		(fp_line
			(start -1.2192 2.06756)
			(end 1.2192 2.06756)
			(stroke
				(width 0.1524)
				(type default)
			)
			(layer "B.SilkS")
		)
		(fp_line
			(start 1.2192 -2.06756)
			(end -1.2192 -2.06756)
			(stroke
				(width 0.1524)
				(type default)
			)
			(layer "B.SilkS")
		)
		(fp_line
			(start 1.2192 2.06756)
			(end 1.2192 -2.06756)
			(stroke
				(width 0.1524)
				(type default)
			)
			(layer "B.SilkS")
		)
		(pad "" np_thru_hole circle
			(at -3.4671 -1.27 270)
			(size 1.0414 1.0414)
			(drill 1.0414)
			(layers "*.Cu" "*.Mask")
			(clearance 0.381)
			(thermal_gap 0.381)
		)
		(pad "" np_thru_hole circle
			(at -3.4671 1.27 270)
			(size 1.0414 1.0414)
			(drill 1.0414)
			(layers "*.Cu" "*.Mask")
			(clearance 0.381)
			(thermal_gap 0.381)
		)
		(pad "" np_thru_hole circle
			(at 2.8829 -1.27 270)
			(size 1.0414 1.0414)
			(drill 1.0414)
			(layers "*.Cu" "*.Mask")
			(clearance 0.381)
			(thermal_gap 0.381)
		)
		(pad "" np_thru_hole circle
			(at 2.8829 1.27 270)
			(size 1.0414 1.0414)
			(drill 1.0414)
			(layers "*.Cu" "*.Mask")
			(clearance 0.381)
			(thermal_gap 0.381)
		)
		(pad "1" smd rect
			(at -0.8255 -0.249936 270)
			(size 0.3048 0.508)
			(layers "B.Cu" "B.Mask" "B.Paste")
			(net "DELTA_L_85_10INCH_IN6_DP")
		)
		(pad "2" smd rect
			(at -0.8255 0.249936 270)
			(size 0.3048 0.508)
			(layers "B.Cu" "B.Mask" "B.Paste")
			(net "DELTA_L_85_10INCH_IN6_DN")
		)
		(pad "3" smd circle
			(at 0 0 180)
			(size 0 0)
			(layers "B.Cu" "B.Mask" "B.Paste")
			(net "DELTA_L_GND_1")
		)
		(zone
			(layers "F.Cu" "B.Cu" "In1.Cu" "In2.Cu" "In3.Cu" "In4.Cu" "In5.Cu" "In6.Cu"
				"In7.Cu" "In8.Cu" "In9.Cu" "In10.Cu" "In11.Cu" "In12.Cu" "In13.Cu" "In14.Cu"
				"In15.Cu" "In16.Cu"
			)
			(hatch none 0.5)
			(connect_pads
				(clearance 0)
			)
			(min_thickness 0.25)
			(keepout
				(tracks not_allowed)
				(vias allowed)
				(pads allowed)
				(copperpour not_allowed)
				(footprints allowed)
			)
			(placement
				(enabled no)
				(sheetname "")
			)
			(fill
				(thermal_gap 0.5)
				(thermal_bridge_width 0.5)
				(island_removal_mode 0)
			)
			(polygon
				(pts
					(arc
						(start 297.998388 1.272794)
						(mid 296.144188 1.272794)
						(end 297.998388 1.272794)
					)
				)
			)
		)
		(zone
			(layers "F.Cu" "B.Cu" "In1.Cu" "In2.Cu" "In3.Cu" "In4.Cu" "In5.Cu" "In6.Cu"
				"In7.Cu" "In8.Cu" "In9.Cu" "In10.Cu" "In11.Cu" "In12.Cu" "In13.Cu" "In14.Cu"
				"In15.Cu" "In16.Cu"
			)
			(hatch none 0.5)
			(connect_pads
				(clearance 0)
			)
			(min_thickness 0.25)
			(keepout
				(tracks not_allowed)
				(vias allowed)
				(pads allowed)
				(copperpour not_allowed)
				(footprints allowed)
			)
			(placement
				(enabled no)
				(sheetname "")
			)
			(fill
				(thermal_gap 0.5)
				(thermal_bridge_width 0.5)
				(island_removal_mode 0)
			)
			(polygon
				(pts
					(arc
						(start 297.998388 3.812794)
						(mid 296.144188 3.812794)
						(end 297.998388 3.812794)
					)
				)
			)
		)
		(zone
			(layers "F.Cu" "B.Cu" "In1.Cu" "In2.Cu" "In3.Cu" "In4.Cu" "In5.Cu" "In6.Cu"
				"In7.Cu" "In8.Cu" "In9.Cu" "In10.Cu" "In11.Cu" "In12.Cu" "In13.Cu" "In14.Cu"
				"In15.Cu" "In16.Cu"
			)
			(hatch none 0.5)
			(connect_pads
				(clearance 0)
			)
			(min_thickness 0.25)
			(keepout
				(tracks not_allowed)
				(vias allowed)
				(pads allowed)
				(copperpour not_allowed)
				(footprints allowed)
			)
			(placement
				(enabled no)
				(sheetname "")
			)
			(fill
				(thermal_gap 0.5)
				(thermal_bridge_width 0.5)
				(island_removal_mode 0)
			)
			(polygon
				(pts
					(arc
						(start 304.348388 1.272794)
						(mid 302.494188 1.272794)
						(end 304.348388 1.272794)
					)
				)
			)
		)
		(zone
			(layers "F.Cu" "B.Cu" "In1.Cu" "In2.Cu" "In3.Cu" "In4.Cu" "In5.Cu" "In6.Cu"
				"In7.Cu" "In8.Cu" "In9.Cu" "In10.Cu" "In11.Cu" "In12.Cu" "In13.Cu" "In14.Cu"
				"In15.Cu" "In16.Cu"
			)
			(hatch none 0.5)
			(connect_pads
				(clearance 0)
			)
			(min_thickness 0.25)
			(keepout
				(tracks not_allowed)
				(vias allowed)
				(pads allowed)
				(copperpour not_allowed)
				(footprints allowed)
			)
			(placement
				(enabled no)
				(sheetname "")
			)
			(fill
				(thermal_gap 0.5)
				(thermal_bridge_width 0.5)
				(island_removal_mode 0)
			)
			(polygon
				(pts
					(arc
						(start 304.348388 3.812794)
						(mid 302.494188 3.812794)
						(end 304.348388 3.812794)
					)
				)
			)
		)
		(zone
			(layer "B.Cu")
			(hatch none 0.5)
			(connect_pads
				(clearance 0)
			)
			(min_thickness 0.25)
			(keepout
				(tracks not_allowed)
				(vias allowed)
				(pads allowed)
				(copperpour not_allowed)
				(footprints allowed)
			)
			(placement
				(enabled no)
				(sheetname "")
			)
			(fill
				(thermal_gap 0.5)
				(thermal_bridge_width 0.5)
				(island_removal_mode 0)
			)
			(polygon
				(pts
					(xy 299.420788 1.994154) (xy 299.420788 2.089658) (xy 300.017688 2.089658) (xy 300.017688 2.496058)
					(xy 299.420788 2.496058) (xy 299.420788 2.58953) (xy 300.017688 2.58953) (xy 300.017688 2.99593)
					(xy 299.420788 2.99593) (xy 299.420788 3.091434) (xy 300.119288 3.091434) (xy 300.119288 1.994154)
				)
			)
		)
	)
	(footprint ""
		(layer "B.Cu")
		(at 110.365794 -383.7432 180)
		(property "Reference" "R910"
			(at 0 0 0)
			(layer "B.SilkS")
			(hide yes)
			(effects
				(font
					(size 1.27 1.27)
				)
				(justify mirror)
			)
		)
		(property "Value" ""
			(at 0 0 0)
			(layer "B.Fab")
			(effects
				(font
					(size 1.27 1.27)
				)
				(justify mirror)
			)
		)
		(duplicate_pad_numbers_are_jumpers no)
		(fp_line
			(start 0.32512 0.175006)
			(end 0.32512 -0.175006)
			(stroke
				(width 0.1)
				(type default)
			)
			(layer "B.Fab")
		)
		(fp_line
			(start 0.32512 -0.175006)
			(end -0.32512 -0.175006)
			(stroke
				(width 0.1)
				(type default)
			)
			(layer "B.Fab")
		)
		(fp_line
			(start -0.32512 0.175006)
			(end 0.32512 0.175006)
			(stroke
				(width 0.1)
				(type default)
			)
			(layer "B.Fab")
		)
		(fp_line
			(start -0.32512 -0.175006)
			(end -0.32512 0.175006)
			(stroke
				(width 0.1)
				(type default)
			)
			(layer "B.Fab")
		)
		(pad "1" smd rect
			(at 0.2667 0)
			(size 0.3048 0.381)
			(layers "B.Cu" "B.Mask" "B.Paste")
			(net "RT_CPU1_P3_SCAN_MODE")
		)
		(pad "2" smd rect
			(at -0.2667 0 180)
			(size 0.3048 0.381)
			(layers "B.Cu" "B.Mask" "B.Paste")
			(net "GND")
		)
	)
)
